FILE_TYPE = MACRO_DRAWING;
SET COLOR_WIRE YELLOW;
SET COLOR_PROP ORANGE;
SET COLOR_DOT WHITE;
SET COLOR_ARC YELLOW;
SET COLOR_BODY GREEN;
SET COLOR_NOTE PURPLE;
SET PROP_DISPLAY VALUE;
SET PAGE_NUMBER P174;
FORCEADD OFFPAGE..1
(-7775 4125);
FORCEPROP 2 LAST $XR4 198 
J 0
(-8507 4125);
DISPLAY 0.638298 (-8507 4125);
PAINT MONO (-8507 4125);
FORCEPROP 2 LAST $XR3 196 
J 0
(-8387 4125);
DISPLAY 0.638298 (-8387 4125);
PAINT MONO (-8387 4125);
FORCEPROP 2 LAST $XR2 195 
J 0
(-8267 4125);
DISPLAY 0.638298 (-8267 4125);
PAINT MONO (-8267 4125);
FORCEPROP 2 LAST $XR1 194 
J 0
(-8147 4125);
DISPLAY 0.638298 (-8147 4125);
PAINT MONO (-8147 4125);
FORCEPROP 2 LAST $XR0 193 
J 0
(-8027 4125);
DISPLAY 0.638298 (-8027 4125);
PAINT MONO (-8027 4125);
FORCEPROP 2 LAST CDS_LIB standard
J 0
(-7775 4125);
DISPLAY INVISIBLE (-7775 4125);
FORCEPROP 1 LAST OFFPAGE TRUE
J 0
(-7450 4000);
DISPLAY 0.872340 (-7450 4000);
PAINT GREEN (-7450 4000);
DISPLAY INVISIBLE (-7450 4000);
FORCEPROP 1 LAST COMMENT_BODY TRUE
J 0
(-7650 4025);
DISPLAY 0.872340 (-7650 4025);
PAINT GREEN (-7650 4025);
DISPLAY INVISIBLE (-7650 4025);
FORCEPROP 2 LAST PATH I1
J 0
(-8025 4175);
DISPLAY 0.680851 (-8025 4175);
DISPLAY INVISIBLE (-8025 4175);
FORCEADD Q_RES..2
(-4375 3575);
FORCEPROP 1 LAST LOCATION PR505
J 0
(-4330 3700);
DISPLAY 0.489362 (-4330 3700);
PAINT SKYBLUE (-4330 3700);
FORCEPROP 0 LAST $SEC 1
J 0
(-4325 3750);
DISPLAY 0.680851 (-4325 3750);
PAINT MONO (-4325 3750);
DISPLAY INVISIBLE (-4325 3750);
FORCEPROP 0 LAST CDS_SEC 1
J 0
(-4325 3750);
DISPLAY 1.021277 (-4325 3750);
DISPLAY INVISIBLE (-4325 3750);
FORCEPROP 1 LASTPIN (-4375 3675) $PN 1
J 0
(-4370 3637);
DISPLAY 0.489362 (-4370 3637);
PAINT MONO (-4370 3637);
FORCEPROP 1 LASTPIN (-4375 3475) $PN 2
J 0
(-4370 3485);
DISPLAY 0.489362 (-4370 3485);
PAINT MONO (-4370 3485);
FORCEPROP 1 LAST PACK_TYPE 0402LF
J 0
(-4335 3400);
DISPLAY 0.489362 (-4335 3400);
PAINT SKYBLUE (-4335 3400);
FORCEPROP 1 LAST TOLERANCE 1%
J 0
(-4330 3600);
DISPLAY 0.489362 (-4330 3600);
PAINT SKYBLUE (-4330 3600);
FORCEPROP 1 LAST MATERIAL EMPTY
J 0
(-4335 3500);
DISPLAY 0.489362 (-4335 3500);
PAINT RED (-4335 3500);
FORCEPROP 1 LAST WATTAGE 1/8W
J 0
(-4335 3550);
DISPLAY 0.489362 (-4335 3550);
PAINT SKYBLUE (-4335 3550);
FORCEPROP 1 LAST VALUE 1.5
J 0
(-4330 3650);
DISPLAY 0.489362 (-4330 3650);
PAINT SKYBLUE (-4330 3650);
FORCEPROP 2 LAST CDS_LIB pure_quanta
J 0
(-4375 3575);
DISPLAY INVISIBLE (-4375 3575);
FORCEPROP 1 LAST PATH I10
J 0
(-4325 3750);
DISPLAY 0.978723 (-4325 3750);
PAINT WHITE (-4325 3750);
DISPLAY INVISIBLE (-4325 3750);
FORCEPROP 1 LAST PART_NUMBER CS-1504FB00
J 0
(-4335 3450);
DISPLAY 0.489362 (-4335 3450);
PAINT SKYBLUE (-4335 3450);
DISPLAY INVISIBLE (-4335 3450);
FORCEADD Q_RES..1
(-3950 3275);
FORCEPROP 1 LAST LOCATION PR367
J 0
(-3975 3325);
DISPLAY 0.489362 (-3975 3325);
PAINT SKYBLUE (-3975 3325);
FORCEPROP 0 LAST $SEC 1
J 0
(-3950 3350);
DISPLAY 0.680851 (-3950 3350);
PAINT MONO (-3950 3350);
DISPLAY INVISIBLE (-3950 3350);
FORCEPROP 0 LAST CDS_SEC 1
J 0
(-3950 3350);
DISPLAY 1.021277 (-3950 3350);
DISPLAY INVISIBLE (-3950 3350);
FORCEPROP 1 LASTPIN (-4050 3275) $PN 1
J 0
(-4038 3287);
DISPLAY 0.489362 (-4038 3287);
PAINT MONO (-4038 3287);
FORCEPROP 1 LASTPIN (-3850 3275) $PN 2
J 0
(-3888 3287);
DISPLAY 0.489362 (-3888 3287);
PAINT MONO (-3888 3287);
FORCEPROP 1 LAST WATTAGE 1/16W
J 0
(-3850 3225);
DISPLAY 0.489362 (-3850 3225);
PAINT SKYBLUE (-3850 3225);
FORCEPROP 1 LAST MATERIAL CHIP
J 0
(-4200 3175);
DISPLAY 0.489362 (-4200 3175);
PAINT SKYBLUE (-4200 3175);
FORCEPROP 1 LAST TOLERANCE 5%
J 0
(-3825 3300);
DISPLAY 0.489362 (-3825 3300);
PAINT SKYBLUE (-3825 3300);
FORCEPROP 1 LAST VALUE 0
J 2
(-4075 3300);
DISPLAY 0.489362 (-4075 3300);
PAINT SKYBLUE (-4075 3300);
FORCEPROP 1 LAST PACK_TYPE 0402LF
J 0
(-3850 3175);
DISPLAY 0.489362 (-3850 3175);
PAINT SKYBLUE (-3850 3175);
FORCEPROP 2 LAST CDS_LIB pure_quanta
J 0
(-3950 3275);
DISPLAY INVISIBLE (-3950 3275);
FORCEPROP 1 LAST PATH I11
J 0
(-4000 3425);
DISPLAY 0.978723 (-4000 3425);
PAINT WHITE (-4000 3425);
DISPLAY INVISIBLE (-4000 3425);
FORCEPROP 1 LAST PART_NUMBER CS00002JB13
J 0
(-4200 3225);
DISPLAY 0.489362 (-4200 3225);
PAINT SKYBLUE (-4200 3225);
DISPLAY INVISIBLE (-4200 3225);
FORCEADD Q_CAP..1
(-4375 4050);
FORCEPROP 1 LAST LOCATION PC188
J 0
(-4325 4150);
DISPLAY 0.489362 (-4325 4150);
PAINT SKYBLUE (-4325 4150);
FORCEPROP 0 LAST $SEC 1
J 0
(-4325 4200);
DISPLAY 0.680851 (-4325 4200);
PAINT MONO (-4325 4200);
DISPLAY INVISIBLE (-4325 4200);
FORCEPROP 0 LAST CDS_SEC 1
J 0
(-4325 4200);
DISPLAY 1.021277 (-4325 4200);
DISPLAY INVISIBLE (-4325 4200);
FORCEPROP 1 LASTPIN (-4375 4150) $PN 1
J 0
(-4365 4130);
DISPLAY 0.489362 (-4365 4130);
PAINT MONO (-4365 4130);
FORCEPROP 1 LASTPIN (-4375 3950) $PN 2
J 0
(-4365 3930);
DISPLAY 0.489362 (-4365 3930);
PAINT MONO (-4365 3930);
FORCEPROP 1 LAST MATERIAL EMPTY
J 0
(-4325 3950);
DISPLAY 0.489362 (-4325 3950);
PAINT RED (-4325 3950);
FORCEPROP 1 LAST VOLTAGE 50V
J 0
(-4325 4050);
DISPLAY 0.489362 (-4325 4050);
PAINT SKYBLUE (-4325 4050);
FORCEPROP 1 LAST VALUE 560PF
J 0
(-4325 4100);
DISPLAY 0.489362 (-4325 4100);
PAINT SKYBLUE (-4325 4100);
FORCEPROP 1 LAST TOLERANCE 10%
J 0
(-4325 4000);
DISPLAY 0.489362 (-4325 4000);
PAINT SKYBLUE (-4325 4000);
FORCEPROP 1 LAST PACK_TYPE C0402
J 0
(-4325 3850);
DISPLAY 0.489362 (-4325 3850);
PAINT SKYBLUE (-4325 3850);
FORCEPROP 2 LAST CDS_LIB pure_quanta
J 0
(-4375 4050);
DISPLAY INVISIBLE (-4375 4050);
FORCEPROP 1 LAST PATH I12
J 0
(-4325 4200);
DISPLAY 0.978723 (-4325 4200);
PAINT WHITE (-4325 4200);
DISPLAY INVISIBLE (-4325 4200);
FORCEPROP 1 LAST PART_NUMBER CH1566K1B09
J 0
(-4325 3900);
DISPLAY 0.489362 (-4325 3900);
PAINT SKYBLUE (-4325 3900);
DISPLAY INVISIBLE (-4325 3900);
FORCEADD UNIVERSAL_GND..1
(-7225 4375);
FORCEPROP 3 LASTPIN (-7225 4425) SIG_NAME GND\g
J 0
(-7215 4435);
DISPLAY 0.659574 (-7215 4435);
PAINT MONO (-7215 4435);
DISPLAY INVISIBLE (-7215 4435);
FORCEPROP 2 LAST CDS_LIB pure_quanta_power
J 0
(-7225 4375);
DISPLAY INVISIBLE (-7225 4375);
FORCEPROP 1 LAST HDL_POWER GND
J 1
(-7200 4300);
DISPLAY 0.872340 (-7200 4300);
PAINT GREEN (-7200 4300);
DISPLAY INVISIBLE (-7200 4300);
FORCEPROP 1 LAST PATH I13
J 0
(-7150 4375);
DISPLAY 0.872340 (-7150 4375);
PAINT AQUA (-7150 4375);
DISPLAY INVISIBLE (-7150 4375);
FORCEADD Q_CAP..1
(-7225 4575);
FORCEPROP 1 LAST LOCATION PC606
J 0
(-7175 4675);
DISPLAY 0.489362 (-7175 4675);
PAINT SKYBLUE (-7175 4675);
FORCEPROP 0 LAST $SEC 1
J 0
(-7175 4725);
DISPLAY 0.680851 (-7175 4725);
PAINT MONO (-7175 4725);
DISPLAY INVISIBLE (-7175 4725);
FORCEPROP 0 LAST CDS_SEC 1
J 0
(-7175 4725);
DISPLAY 1.021277 (-7175 4725);
DISPLAY INVISIBLE (-7175 4725);
FORCEPROP 1 LASTPIN (-7225 4675) $PN 1
J 0
(-7215 4655);
DISPLAY 0.489362 (-7215 4655);
PAINT MONO (-7215 4655);
FORCEPROP 1 LASTPIN (-7225 4475) $PN 2
J 0
(-7215 4455);
DISPLAY 0.489362 (-7215 4455);
PAINT MONO (-7215 4455);
FORCEPROP 1 LAST MATERIAL X6S
J 0
(-7175 4475);
DISPLAY 0.489362 (-7175 4475);
PAINT SKYBLUE (-7175 4475);
FORCEPROP 1 LAST PACK_TYPE C0402
J 0
(-7175 4375);
DISPLAY 0.489362 (-7175 4375);
PAINT SKYBLUE (-7175 4375);
FORCEPROP 1 LAST VOLTAGE 10V
J 0
(-7175 4575);
DISPLAY 0.489362 (-7175 4575);
PAINT SKYBLUE (-7175 4575);
FORCEPROP 1 LAST VALUE 2.2UF
J 0
(-7175 4625);
DISPLAY 0.489362 (-7175 4625);
PAINT SKYBLUE (-7175 4625);
FORCEPROP 1 LAST TOLERANCE 10%
J 0
(-7175 4525);
DISPLAY 0.489362 (-7175 4525);
PAINT SKYBLUE (-7175 4525);
FORCEPROP 2 LAST CDS_LIB pure_quanta
J 0
(-7225 4575);
DISPLAY INVISIBLE (-7225 4575);
FORCEPROP 1 LAST PATH I14
J 0
(-7175 4725);
DISPLAY 0.978723 (-7175 4725);
PAINT WHITE (-7175 4725);
DISPLAY INVISIBLE (-7175 4725);
FORCEPROP 1 LAST PART_NUMBER CH5222KEB01
J 0
(-7175 4425);
DISPLAY 0.489362 (-7175 4425);
PAINT SKYBLUE (-7175 4425);
DISPLAY INVISIBLE (-7175 4425);
FORCEADD Q_RES..2
(-7225 5050);
FORCEPROP 1 LAST LOCATION PR364
J 0
(-7180 5150);
DISPLAY 0.489362 (-7180 5150);
PAINT SKYBLUE (-7180 5150);
FORCEPROP 0 LAST $SEC 1
J 0
(-7175 5225);
DISPLAY 0.680851 (-7175 5225);
PAINT MONO (-7175 5225);
DISPLAY INVISIBLE (-7175 5225);
FORCEPROP 0 LAST CDS_SEC 1
J 0
(-7175 5225);
DISPLAY 1.021277 (-7175 5225);
DISPLAY INVISIBLE (-7175 5225);
FORCEPROP 1 LASTPIN (-7225 5150) $PN 1
J 0
(-7220 5112);
DISPLAY 0.489362 (-7220 5112);
PAINT MONO (-7220 5112);
FORCEPROP 1 LASTPIN (-7225 4950) $PN 2
J 0
(-7220 4960);
DISPLAY 0.489362 (-7220 4960);
PAINT MONO (-7220 4960);
FORCEPROP 1 LAST WATTAGE 1/16W
J 0
(-7175 5000);
DISPLAY 0.489362 (-7175 5000);
PAINT SKYBLUE (-7175 5000);
FORCEPROP 1 LAST MATERIAL CHIP
J 0
(-7175 4950);
DISPLAY 0.489362 (-7175 4950);
PAINT SKYBLUE (-7175 4950);
FORCEPROP 1 LAST TOLERANCE 1%
J 0
(-7175 5050);
DISPLAY 0.489362 (-7175 5050);
PAINT SKYBLUE (-7175 5050);
FORCEPROP 1 LAST VALUE 2.2
J 0
(-7175 5100);
DISPLAY 0.489362 (-7175 5100);
PAINT SKYBLUE (-7175 5100);
FORCEPROP 1 LAST PACK_TYPE 0402LF
J 0
(-7175 4850);
DISPLAY 0.489362 (-7175 4850);
PAINT SKYBLUE (-7175 4850);
FORCEPROP 2 LAST CDS_LIB pure_quanta
J 0
(-7225 5050);
DISPLAY INVISIBLE (-7225 5050);
FORCEPROP 1 LAST PATH I15
J 0
(-7175 5225);
DISPLAY 0.978723 (-7175 5225);
PAINT WHITE (-7175 5225);
DISPLAY INVISIBLE (-7175 5225);
FORCEPROP 1 LAST PART_NUMBER CS-2202FB01
J 0
(-7175 4900);
DISPLAY 0.489362 (-7175 4900);
PAINT SKYBLUE (-7175 4900);
DISPLAY INVISIBLE (-7175 4900);
FORCEADD VCC_CORE..1
(-7225 5450);
FORCEPROP 3 LASTPIN (-7225 5400) SIG_NAME PVDDCR_CPU0_P0_PVCC\g
J 0
(-7215 5410);
DISPLAY 0.659574 (-7215 5410);
PAINT MONO (-7215 5410);
DISPLAY INVISIBLE (-7215 5410);
FORCEPROP 1 LAST HDL_POWER PVDDCR_CPU0_P0_PVCC
J 1
(-7225 5500);
DISPLAY 0.489362 (-7225 5500);
PAINT GREEN (-7225 5500);
FORCEPROP 2 LAST CDS_LIB pure_quanta_power
J 0
(-7225 5450);
DISPLAY INVISIBLE (-7225 5450);
FORCEPROP 1 LAST PATH I16
J 0
(-7175 5475);
DISPLAY 0.872340 (-7175 5475);
PAINT AQUA (-7175 5475);
DISPLAY INVISIBLE (-7175 5475);
FORCEADD OFFPAGE..2
R 2
(-6875 4225);
FORCEPROP 2 LAST $XR0 193 
J 0
(-7130 4225);
DISPLAY 0.638298 (-7130 4225);
PAINT MONO (-7130 4225);
FORCEPROP 2 LAST CDS_LIB standard
J 2
(-6875 4225);
DISPLAY INVISIBLE (-6875 4225);
FORCEPROP 1 LAST OFFPAGE TRUE
J 2
(-7200 4100);
DISPLAY 0.872340 (-7200 4100);
PAINT GREEN (-7200 4100);
DISPLAY INVISIBLE (-7200 4100);
FORCEPROP 1 LAST COMMENT_BODY TRUE
J 2
(-6830 4130);
DISPLAY 0.872340 (-6830 4130);
PAINT GREEN (-6830 4130);
DISPLAY INVISIBLE (-6830 4130);
FORCEPROP 2 LAST PATH I17
J 0
(-7125 4275);
DISPLAY 0.680851 (-7125 4275);
DISPLAY INVISIBLE (-7125 4275);
FORCEADD UNIVERSAL_GND..1
(-6875 4800);
FORCEPROP 3 LASTPIN (-6875 4850) SIG_NAME GND\g
J 0
(-6865 4860);
DISPLAY 0.659574 (-6865 4860);
PAINT MONO (-6865 4860);
DISPLAY INVISIBLE (-6865 4860);
FORCEPROP 2 LAST CDS_LIB pure_quanta_power
J 0
(-6875 4800);
DISPLAY INVISIBLE (-6875 4800);
FORCEPROP 1 LAST HDL_POWER GND
J 1
(-6850 4725);
DISPLAY 0.872340 (-6850 4725);
PAINT GREEN (-6850 4725);
DISPLAY INVISIBLE (-6850 4725);
FORCEPROP 1 LAST PATH I18
J 0
(-6800 4800);
DISPLAY 0.872340 (-6800 4800);
PAINT AQUA (-6800 4800);
DISPLAY INVISIBLE (-6800 4800);
FORCEADD Q_CAP..1
(-6875 5050);
FORCEPROP 1 LAST LOCATION PC607_SOP0_3
J 0
(-6825 5150);
DISPLAY 0.489362 (-6825 5150);
PAINT SKYBLUE (-6825 5150);
FORCEPROP 0 LAST $SEC 1
J 0
(-6825 5200);
DISPLAY 0.680851 (-6825 5200);
PAINT MONO (-6825 5200);
DISPLAY INVISIBLE (-6825 5200);
FORCEPROP 0 LAST CDS_SEC 1
J 0
(-6825 5200);
DISPLAY 1.021277 (-6825 5200);
DISPLAY INVISIBLE (-6825 5200);
FORCEPROP 1 LASTPIN (-6875 5150) $PN 1
J 0
(-6865 5130);
DISPLAY 0.489362 (-6865 5130);
PAINT MONO (-6865 5130);
FORCEPROP 1 LASTPIN (-6875 4950) $PN 2
J 0
(-6865 4930);
DISPLAY 0.489362 (-6865 4930);
PAINT MONO (-6865 4930);
FORCEPROP 1 LAST PACK_TYPE C0402
J 0
(-6825 4850);
DISPLAY 0.489362 (-6825 4850);
PAINT SKYBLUE (-6825 4850);
FORCEPROP 1 LAST VOLTAGE 10V
J 0
(-6825 5050);
DISPLAY 0.489362 (-6825 5050);
PAINT SKYBLUE (-6825 5050);
FORCEPROP 1 LAST VALUE 2.2UF
J 0
(-6825 5100);
DISPLAY 0.489362 (-6825 5100);
PAINT SKYBLUE (-6825 5100);
FORCEPROP 1 LAST TOLERANCE 10%
J 0
(-6825 5000);
DISPLAY 0.489362 (-6825 5000);
PAINT SKYBLUE (-6825 5000);
FORCEPROP 1 LAST MATERIAL X6S
J 0
(-6825 4950);
DISPLAY 0.489362 (-6825 4950);
PAINT SKYBLUE (-6825 4950);
FORCEPROP 2 LAST CDS_LIB pure_quanta
J 0
(-6875 5050);
DISPLAY INVISIBLE (-6875 5050);
FORCEPROP 1 LAST PATH I19
J 0
(-6825 5200);
DISPLAY 0.978723 (-6825 5200);
PAINT WHITE (-6825 5200);
DISPLAY INVISIBLE (-6825 5200);
FORCEPROP 1 LAST PART_NUMBER CH5222KEB01
J 0
(-6825 4900);
DISPLAY 0.489362 (-6825 4900);
PAINT SKYBLUE (-6825 4900);
DISPLAY INVISIBLE (-6825 4900);
FORCEADD Q_CAP..1
(-7550 3950);
FORCEPROP 1 LAST LOCATION PC605_9
J 0
(-7500 4050);
DISPLAY 0.489362 (-7500 4050);
PAINT SKYBLUE (-7500 4050);
FORCEPROP 0 LAST $SEC 1
J 0
(-7500 4075);
DISPLAY 0.680851 (-7500 4075);
PAINT MONO (-7500 4075);
DISPLAY INVISIBLE (-7500 4075);
FORCEPROP 0 LAST CDS_SEC 1
J 0
(-7500 4075);
DISPLAY 1.021277 (-7500 4075);
DISPLAY INVISIBLE (-7500 4075);
FORCEPROP 1 LASTPIN (-7550 4050) $PN 1
J 0
(-7540 4030);
DISPLAY 0.489362 (-7540 4030);
PAINT MONO (-7540 4030);
FORCEPROP 1 LASTPIN (-7550 3850) $PN 2
J 0
(-7540 3830);
DISPLAY 0.489362 (-7540 3830);
PAINT MONO (-7540 3830);
FORCEPROP 1 LAST PACK_TYPE 0402
J 0
(-7500 3750);
DISPLAY 0.489362 (-7500 3750);
PAINT SKYBLUE (-7500 3750);
FORCEPROP 1 LAST VOLTAGE 25V
J 0
(-7500 3950);
DISPLAY 0.489362 (-7500 3950);
PAINT SKYBLUE (-7500 3950);
FORCEPROP 1 LAST VALUE 0.1UF
J 0
(-7500 4000);
DISPLAY 0.489362 (-7500 4000);
PAINT SKYBLUE (-7500 4000);
FORCEPROP 1 LAST TOLERANCE 10%
J 0
(-7500 3900);
DISPLAY 0.489362 (-7500 3900);
PAINT SKYBLUE (-7500 3900);
FORCEPROP 1 LAST MATERIAL X7R
J 0
(-7500 3850);
DISPLAY 0.489362 (-7500 3850);
PAINT SKYBLUE (-7500 3850);
FORCEPROP 2 LAST CDS_LIB pure_quanta
J 0
(-7550 3950);
DISPLAY INVISIBLE (-7550 3950);
FORCEPROP 1 LAST PATH I2
J 0
(-7500 4100);
DISPLAY 0.978723 (-7500 4100);
PAINT WHITE (-7500 4100);
DISPLAY INVISIBLE (-7500 4100);
FORCEPROP 1 LAST PART_NUMBER CH4104K1B00
J 0
(-7500 3800);
DISPLAY 0.489362 (-7500 3800);
PAINT SKYBLUE (-7500 3800);
DISPLAY INVISIBLE (-7500 3800);
FORCEADD Q_RES..1
(-4425 4575);
FORCEPROP 1 LAST LOCATION PR366
J 0
(-4450 4625);
DISPLAY 0.489362 (-4450 4625);
PAINT SKYBLUE (-4450 4625);
FORCEPROP 0 LAST $SEC 1
J 0
(-4400 4650);
DISPLAY 0.680851 (-4400 4650);
PAINT MONO (-4400 4650);
DISPLAY INVISIBLE (-4400 4650);
FORCEPROP 0 LAST CDS_SEC 1
J 0
(-4400 4650);
DISPLAY 1.021277 (-4400 4650);
DISPLAY INVISIBLE (-4400 4650);
FORCEPROP 1 LASTPIN (-4525 4575) $PN 1
J 0
(-4513 4587);
DISPLAY 0.489362 (-4513 4587);
PAINT MONO (-4513 4587);
FORCEPROP 1 LASTPIN (-4325 4575) $PN 2
J 0
(-4363 4587);
DISPLAY 0.489362 (-4363 4587);
PAINT MONO (-4363 4587);
FORCEPROP 1 LAST TOLERANCE 1%
J 0
(-4300 4600);
DISPLAY 0.489362 (-4300 4600);
PAINT SKYBLUE (-4300 4600);
FORCEPROP 1 LAST WATTAGE 1/16W
J 0
(-4325 4525);
DISPLAY 0.489362 (-4325 4525);
PAINT SKYBLUE (-4325 4525);
FORCEPROP 1 LAST PACK_TYPE 0402LF
J 0
(-4325 4475);
DISPLAY 0.489362 (-4325 4475);
PAINT SKYBLUE (-4325 4475);
FORCEPROP 1 LAST MATERIAL CHIP
J 0
(-4675 4475);
DISPLAY 0.489362 (-4675 4475);
PAINT SKYBLUE (-4675 4475);
FORCEPROP 1 LAST VALUE 5.6
J 2
(-4550 4600);
DISPLAY 0.489362 (-4550 4600);
PAINT SKYBLUE (-4550 4600);
FORCEPROP 2 LAST CDS_LIB pure_quanta
J 0
(-4425 4575);
DISPLAY INVISIBLE (-4425 4575);
FORCEPROP 1 LAST PATH I20
J 0
(-4475 4725);
DISPLAY 0.978723 (-4475 4725);
PAINT WHITE (-4475 4725);
DISPLAY INVISIBLE (-4475 4725);
FORCEPROP 1 LAST PART_NUMBER CS-5602FB01
J 0
(-4675 4525);
DISPLAY 0.489362 (-4675 4525);
PAINT SKYBLUE (-4675 4525);
DISPLAY INVISIBLE (-4675 4525);
FORCEADD Q_CAP..1
(-4525 5100);
FORCEPROP 1 LAST LOCATION PC608_3
J 0
(-4475 5200);
DISPLAY 0.489362 (-4475 5200);
PAINT SKYBLUE (-4475 5200);
FORCEPROP 0 LAST $SEC 1
J 0
(-4475 5225);
DISPLAY 0.680851 (-4475 5225);
PAINT MONO (-4475 5225);
DISPLAY INVISIBLE (-4475 5225);
FORCEPROP 0 LAST CDS_SEC 1
J 0
(-4475 5225);
DISPLAY 1.021277 (-4475 5225);
DISPLAY INVISIBLE (-4475 5225);
FORCEPROP 1 LASTPIN (-4525 5200) $PN 1
J 0
(-4515 5180);
DISPLAY 0.489362 (-4515 5180);
PAINT MONO (-4515 5180);
FORCEPROP 1 LASTPIN (-4525 5000) $PN 2
J 0
(-4515 4980);
DISPLAY 0.489362 (-4515 4980);
PAINT MONO (-4515 4980);
FORCEPROP 1 LAST MATERIAL X6S
J 0
(-4475 5000);
DISPLAY 0.489362 (-4475 5000);
PAINT SKYBLUE (-4475 5000);
FORCEPROP 1 LAST VALUE 1UF
J 0
(-4475 5150);
DISPLAY 0.489362 (-4475 5150);
PAINT SKYBLUE (-4475 5150);
FORCEPROP 1 LAST VOLTAGE 25V
J 0
(-4475 5100);
DISPLAY 0.489362 (-4475 5100);
PAINT SKYBLUE (-4475 5100);
FORCEPROP 1 LAST TOLERANCE 10%
J 0
(-4475 5050);
DISPLAY 0.489362 (-4475 5050);
PAINT SKYBLUE (-4475 5050);
FORCEPROP 1 LAST PACK_TYPE C0402
J 0
(-4475 4900);
DISPLAY 0.489362 (-4475 4900);
PAINT SKYBLUE (-4475 4900);
FORCEPROP 2 LAST CDS_LIB pure_quanta
J 0
(-4525 5100);
DISPLAY INVISIBLE (-4525 5100);
FORCEPROP 1 LAST PATH I21
J 0
(-4475 5250);
DISPLAY 0.978723 (-4475 5250);
PAINT WHITE (-4475 5250);
DISPLAY INVISIBLE (-4475 5250);
FORCEPROP 1 LAST PART_NUMBER CH5104KEB02
J 0
(-4475 4950);
DISPLAY 0.489362 (-4475 4950);
PAINT SKYBLUE (-4475 4950);
DISPLAY INVISIBLE (-4475 4950);
FORCEADD Q_CAP..1
(-4200 5100);
FORCEPROP 1 LAST LOCATION PC610_3
J 0
(-4150 5200);
DISPLAY 0.489362 (-4150 5200);
PAINT SKYBLUE (-4150 5200);
FORCEPROP 0 LAST $SEC 1
J 0
(-4150 5225);
DISPLAY 0.680851 (-4150 5225);
PAINT MONO (-4150 5225);
DISPLAY INVISIBLE (-4150 5225);
FORCEPROP 0 LAST CDS_SEC 1
J 0
(-4150 5225);
DISPLAY 1.021277 (-4150 5225);
DISPLAY INVISIBLE (-4150 5225);
FORCEPROP 1 LASTPIN (-4200 5200) $PN 1
J 0
(-4190 5180);
DISPLAY 0.489362 (-4190 5180);
PAINT MONO (-4190 5180);
FORCEPROP 1 LASTPIN (-4200 5000) $PN 2
J 0
(-4190 4980);
DISPLAY 0.489362 (-4190 4980);
PAINT MONO (-4190 4980);
FORCEPROP 1 LAST PACK_TYPE C0805
J 0
(-4150 4900);
DISPLAY 0.489362 (-4150 4900);
PAINT SKYBLUE (-4150 4900);
FORCEPROP 1 LAST MATERIAL X6S
J 0
(-4150 5000);
DISPLAY 0.489362 (-4150 5000);
PAINT SKYBLUE (-4150 5000);
FORCEPROP 1 LAST TOLERANCE 20%
J 0
(-4150 5050);
DISPLAY 0.489362 (-4150 5050);
PAINT SKYBLUE (-4150 5050);
FORCEPROP 1 LAST VOLTAGE 16V
J 0
(-4150 5100);
DISPLAY 0.489362 (-4150 5100);
PAINT SKYBLUE (-4150 5100);
FORCEPROP 1 LAST VALUE 22UF
J 0
(-4150 5150);
DISPLAY 0.489362 (-4150 5150);
PAINT SKYBLUE (-4150 5150);
FORCEPROP 2 LAST CDS_LIB pure_quanta
J 0
(-4200 5100);
DISPLAY INVISIBLE (-4200 5100);
FORCEPROP 1 LAST PATH I22
J 0
(-4150 5250);
DISPLAY 0.978723 (-4150 5250);
PAINT WHITE (-4150 5250);
DISPLAY INVISIBLE (-4150 5250);
FORCEPROP 1 LAST PART_NUMBER CH6223MEA01
J 0
(-4150 4950);
DISPLAY 0.489362 (-4150 4950);
PAINT SKYBLUE (-4150 4950);
DISPLAY INVISIBLE (-4150 4950);
FORCEADD UNIVERSAL_GND..1
(-3975 3875);
FORCEPROP 3 LASTPIN (-3975 3925) SIG_NAME GND\g
J 0
(-3965 3935);
DISPLAY 0.659574 (-3965 3935);
PAINT MONO (-3965 3935);
DISPLAY INVISIBLE (-3965 3935);
FORCEPROP 2 LAST CDS_LIB pure_quanta_power
J 0
(-3975 3875);
DISPLAY INVISIBLE (-3975 3875);
FORCEPROP 1 LAST HDL_POWER GND
J 1
(-3950 3800);
DISPLAY 0.872340 (-3950 3800);
PAINT GREEN (-3950 3800);
DISPLAY INVISIBLE (-3950 3800);
FORCEPROP 1 LAST PATH I23
J 0
(-3900 3875);
DISPLAY 0.872340 (-3900 3875);
PAINT AQUA (-3900 3875);
DISPLAY INVISIBLE (-3900 3875);
FORCEADD Q_INDUCTOR..1
(-3775 4000);
FORCEPROP 1 LAST LOCATION PL62
J 0
(-3925 4125);
DISPLAY 0.468085 (-3925 4125);
PAINT SKYBLUE (-3925 4125);
FORCEPROP 0 LAST $SEC 1
J 0
(-3925 4225);
DISPLAY 0.680851 (-3925 4225);
PAINT MONO (-3925 4225);
DISPLAY INVISIBLE (-3925 4225);
FORCEPROP 0 LAST CDS_SEC 1
J 0
(-3925 4175);
DISPLAY 0.680851 (-3925 4175);
DISPLAY INVISIBLE (-3925 4175);
FORCEPROP 0 LASTPIN (-3875 3975) $PN 1
J 2
(-3885 3985);
DISPLAY 0.680851 (-3885 3985);
PAINT MONO (-3885 3985);
FORCEPROP 0 LASTPIN (-3675 3975) $PN 2
J 0
(-3665 3985);
DISPLAY 0.680851 (-3665 3985);
PAINT MONO (-3665 3985);
FORCEPROP 2 LAST PACK_TYPE SMLF
J 0
(-3925 4175);
DISPLAY 0.765957 (-3925 4175);
FORCEPROP 1 LAST MATERIAL IND
J 0
(-3925 4075);
DISPLAY 0.468085 (-3925 4075);
PAINT SKYBLUE (-3925 4075);
FORCEPROP 2 LAST VALUE 0.22UH/33A
J 0
(-3925 4100);
DISPLAY 0.489362 (-3925 4100);
PAINT SKYBLUE (-3925 4100);
FORCEPROP 2 LAST CDS_LIB pure_quanta
J 0
(-3775 4000);
DISPLAY INVISIBLE (-3775 4000);
FORCEPROP 1 LAST NEEDS_NO_SIZE TRUE
J 0
(-3775 4000);
DISPLAY 0.468085 (-3775 4000);
PAINT GREEN (-3775 4000);
DISPLAY INVISIBLE (-3775 4000);
FORCEPROP 1 LAST PATH I24
J 0
(-3700 4055);
DISPLAY 0.723404 (-3700 4055);
PAINT GREEN (-3700 4055);
DISPLAY INVISIBLE (-3700 4055);
FORCEPROP 1 LAST PART_NUMBER CV+22Y0EZ00
J 0
(-3925 4050);
DISPLAY 0.468085 (-3925 4050);
PAINT SKYBLUE (-3925 4050);
DISPLAY INVISIBLE (-3925 4050);
FORCEADD Q_INDUCTOR4P_14..1
(-2825 4100);
FORCEPROP 1 LAST LOCATION PL66
J 0
(-3050 4355);
DISPLAY 0.489362 (-3050 4355);
PAINT SKYBLUE (-3050 4355);
FORCEPROP 0 LAST $SEC 1
J 0
(-3050 4500);
DISPLAY 0.680851 (-3050 4500);
PAINT MONO (-3050 4500);
DISPLAY INVISIBLE (-3050 4500);
FORCEPROP 0 LAST CDS_SEC 1
J 0
(-3050 4500);
DISPLAY 1.021277 (-3050 4500);
DISPLAY INVISIBLE (-3050 4500);
FORCEPROP 0 LASTPIN (-3225 4225) $PN 1
J 2
(-3235 4235);
DISPLAY 0.489362 (-3235 4235);
PAINT MONO (-3235 4235);
FORCEPROP 0 LASTPIN (-3225 3975) $PN 2
J 2
(-3235 3985);
DISPLAY 0.489362 (-3235 3985);
PAINT MONO (-3235 3985);
FORCEPROP 0 LASTPIN (-2425 3975) $PN 3
J 0
(-2415 3985);
DISPLAY 0.489362 (-2415 3985);
PAINT MONO (-2415 3985);
FORCEPROP 0 LASTPIN (-2425 4225) $PN 4
J 0
(-2415 4235);
DISPLAY 0.489362 (-2415 4235);
PAINT MONO (-2415 4235);
FORCEPROP 1 LAST MATERIAL IND
J 0
(-3050 4310);
DISPLAY 0.489362 (-3050 4310);
PAINT SKYBLUE (-3050 4310);
FORCEPROP 2 LAST VALUE 150NH
J 0
(-3050 4400);
DISPLAY 0.489362 (-3050 4400);
PAINT SKYBLUE (-3050 4400);
FORCEPROP 2 LAST PART_TYPE SMLF
J 0
(-3050 4450);
DISPLAY 1.021277 (-3050 4450);
FORCEPROP 1 LAST NEEDS_NO_SIZE TRUE
J 0
(-2825 4100);
DISPLAY 0.468085 (-2825 4100);
PAINT GREEN (-2825 4100);
DISPLAY INVISIBLE (-2825 4100);
FORCEPROP 2 LAST CDS_LIB pure_quanta
J 0
(-2825 4100);
DISPLAY INVISIBLE (-2825 4100);
FORCEPROP 1 LAST PATH I25
J 0
(-2625 4255);
DISPLAY 0.723404 (-2625 4255);
PAINT GREEN (-2625 4255);
DISPLAY INVISIBLE (-2625 4255);
FORCEPROP 1 LAST PART_NUMBER CV+15^0TZ04
J 0
(-3050 4260);
DISPLAY 0.489362 (-3050 4260);
PAINT SKYBLUE (-3050 4260);
DISPLAY INVISIBLE (-3050 4260);
FORCEADD OFFPAGE..3
(-1950 3975);
FORCEPROP 2 LAST $XR0 198 
J 0
(-1526 3975);
DISPLAY 0.638298 (-1526 3975);
PAINT MONO (-1526 3975);
FORCEPROP 2 LAST CDS_LIB standard
J 2
(-1950 3975);
DISPLAY INVISIBLE (-1950 3975);
FORCEPROP 1 LAST OFFPAGE TRUE
J 0
(-1625 3850);
DISPLAY 0.872340 (-1625 3850);
PAINT GREEN (-1625 3850);
DISPLAY INVISIBLE (-1625 3850);
FORCEPROP 1 LAST COMMENT_BODY TRUE
J 0
(-2000 3875);
DISPLAY 0.872340 (-2000 3875);
PAINT GREEN (-2000 3875);
DISPLAY INVISIBLE (-2000 3875);
FORCEPROP 2 LAST PATH I26
J 0
(-1525 4025);
DISPLAY 0.680851 (-1525 4025);
DISPLAY INVISIBLE (-1525 4025);
FORCEADD Q_CAP..1
(-1650 4050);
FORCEPROP 1 LAST LOCATION PC614_3
J 0
(-1600 4150);
DISPLAY 0.489362 (-1600 4150);
PAINT SKYBLUE (-1600 4150);
FORCEPROP 0 LAST $SEC 1
J 0
(-1600 4175);
DISPLAY 0.680851 (-1600 4175);
PAINT MONO (-1600 4175);
DISPLAY INVISIBLE (-1600 4175);
FORCEPROP 0 LAST CDS_SEC 1
J 0
(-1600 4175);
DISPLAY 1.021277 (-1600 4175);
DISPLAY INVISIBLE (-1600 4175);
FORCEPROP 1 LASTPIN (-1650 4150) $PN 1
J 0
(-1640 4130);
DISPLAY 0.489362 (-1640 4130);
PAINT MONO (-1640 4130);
FORCEPROP 1 LASTPIN (-1650 3950) $PN 2
J 0
(-1640 3930);
DISPLAY 0.489362 (-1640 3930);
PAINT MONO (-1640 3930);
FORCEPROP 1 LAST PACK_TYPE C0805
J 0
(-1600 3850);
DISPLAY 0.489362 (-1600 3850);
PAINT SKYBLUE (-1600 3850);
FORCEPROP 1 LAST MATERIAL X6S
J 0
(-1600 3950);
DISPLAY 0.489362 (-1600 3950);
PAINT SKYBLUE (-1600 3950);
FORCEPROP 1 LAST TOLERANCE 20%
J 0
(-1600 4000);
DISPLAY 0.489362 (-1600 4000);
PAINT SKYBLUE (-1600 4000);
FORCEPROP 1 LAST VALUE 22UF
J 0
(-1600 4100);
DISPLAY 0.489362 (-1600 4100);
PAINT SKYBLUE (-1600 4100);
FORCEPROP 1 LAST VOLTAGE 4V
J 0
(-1600 4050);
DISPLAY 0.489362 (-1600 4050);
PAINT SKYBLUE (-1600 4050);
FORCEPROP 2 LAST CDS_LIB pure_quanta
J 0
(-1650 4050);
DISPLAY INVISIBLE (-1650 4050);
FORCEPROP 1 LAST PATH I27
J 0
(-1600 4200);
DISPLAY 0.978723 (-1600 4200);
PAINT WHITE (-1600 4200);
DISPLAY INVISIBLE (-1600 4200);
FORCEPROP 1 LAST PART_NUMBER CH622KMEA03
J 0
(-1600 3900);
DISPLAY 0.489362 (-1600 3900);
PAINT SKYBLUE (-1600 3900);
DISPLAY INVISIBLE (-1600 3900);
FORCEADD UNIVERSAL_GND..1
(-1225 3700);
FORCEPROP 3 LASTPIN (-1225 3750) SIG_NAME GND\g
J 0
(-1215 3760);
DISPLAY 0.659574 (-1215 3760);
PAINT MONO (-1215 3760);
DISPLAY INVISIBLE (-1215 3760);
FORCEPROP 2 LAST CDS_LIB pure_quanta_power
J 0
(-1225 3700);
DISPLAY INVISIBLE (-1225 3700);
FORCEPROP 1 LAST HDL_POWER GND
J 1
(-1200 3625);
DISPLAY 0.872340 (-1200 3625);
PAINT GREEN (-1200 3625);
DISPLAY INVISIBLE (-1200 3625);
FORCEPROP 1 LAST PATH I28
J 0
(-1150 3700);
DISPLAY 0.872340 (-1150 3700);
PAINT AQUA (-1150 3700);
DISPLAY INVISIBLE (-1150 3700);
FORCEADD Q_CAP..1
(-1225 4050);
FORCEPROP 1 LAST LOCATION PC615_3
J 0
(-1175 4150);
DISPLAY 0.489362 (-1175 4150);
PAINT SKYBLUE (-1175 4150);
FORCEPROP 0 LAST $SEC 1
J 0
(-1175 4175);
DISPLAY 0.680851 (-1175 4175);
PAINT MONO (-1175 4175);
DISPLAY INVISIBLE (-1175 4175);
FORCEPROP 0 LAST CDS_SEC 1
J 0
(-1175 4175);
DISPLAY 1.021277 (-1175 4175);
DISPLAY INVISIBLE (-1175 4175);
FORCEPROP 1 LASTPIN (-1225 4150) $PN 1
J 0
(-1215 4130);
DISPLAY 0.489362 (-1215 4130);
PAINT MONO (-1215 4130);
FORCEPROP 1 LASTPIN (-1225 3950) $PN 2
J 0
(-1215 3930);
DISPLAY 0.489362 (-1215 3930);
PAINT MONO (-1215 3930);
FORCEPROP 1 LAST VALUE 22UF
J 0
(-1175 4100);
DISPLAY 0.489362 (-1175 4100);
PAINT SKYBLUE (-1175 4100);
FORCEPROP 1 LAST PACK_TYPE C0805
J 0
(-1175 3850);
DISPLAY 0.489362 (-1175 3850);
PAINT SKYBLUE (-1175 3850);
FORCEPROP 1 LAST MATERIAL X6S
J 0
(-1175 3950);
DISPLAY 0.489362 (-1175 3950);
PAINT SKYBLUE (-1175 3950);
FORCEPROP 1 LAST TOLERANCE 20%
J 0
(-1175 4000);
DISPLAY 0.489362 (-1175 4000);
PAINT SKYBLUE (-1175 4000);
FORCEPROP 1 LAST VOLTAGE 4V
J 0
(-1175 4050);
DISPLAY 0.489362 (-1175 4050);
PAINT SKYBLUE (-1175 4050);
FORCEPROP 2 LAST CDS_LIB pure_quanta
J 0
(-1225 4050);
DISPLAY INVISIBLE (-1225 4050);
FORCEPROP 1 LAST PATH I29
J 0
(-1175 4200);
DISPLAY 0.978723 (-1175 4200);
PAINT WHITE (-1175 4200);
DISPLAY INVISIBLE (-1175 4200);
FORCEPROP 1 LAST PART_NUMBER CH622KMEA03
J 0
(-1175 3900);
DISPLAY 0.489362 (-1175 3900);
PAINT SKYBLUE (-1175 3900);
DISPLAY INVISIBLE (-1175 3900);
FORCEADD UNIVERSAL_GND..1
(-7550 3675);
FORCEPROP 3 LASTPIN (-7550 3725) SIG_NAME GND\g
J 0
(-7540 3735);
DISPLAY 0.659574 (-7540 3735);
PAINT MONO (-7540 3735);
DISPLAY INVISIBLE (-7540 3735);
FORCEPROP 2 LAST CDS_LIB pure_quanta_power
J 0
(-7550 3675);
DISPLAY INVISIBLE (-7550 3675);
FORCEPROP 1 LAST HDL_POWER GND
J 1
(-7525 3600);
DISPLAY 0.872340 (-7525 3600);
PAINT GREEN (-7525 3600);
DISPLAY INVISIBLE (-7525 3600);
FORCEPROP 1 LAST PATH I3
J 0
(-7475 3675);
DISPLAY 0.872340 (-7475 3675);
PAINT AQUA (-7475 3675);
DISPLAY INVISIBLE (-7475 3675);
FORCEADD Q_CAP..1
(-3600 4450);
FORCEPROP 1 LAST LOCATION PC612
J 0
(-3550 4575);
DISPLAY 0.489362 (-3550 4575);
PAINT SKYBLUE (-3550 4575);
FORCEPROP 0 LAST $SEC 1
J 0
(-3550 4600);
DISPLAY 0.680851 (-3550 4600);
PAINT MONO (-3550 4600);
DISPLAY INVISIBLE (-3550 4600);
FORCEPROP 0 LAST CDS_SEC 1
J 0
(-3550 4600);
DISPLAY 1.021277 (-3550 4600);
DISPLAY INVISIBLE (-3550 4600);
FORCEPROP 1 LASTPIN (-3600 4550) $PN 1
J 0
(-3590 4530);
DISPLAY 0.489362 (-3590 4530);
PAINT MONO (-3590 4530);
FORCEPROP 1 LASTPIN (-3600 4350) $PN 2
J 0
(-3590 4330);
DISPLAY 0.489362 (-3590 4330);
PAINT MONO (-3590 4330);
FORCEPROP 1 LAST PACK_TYPE 0402
J 0
(-3550 4275);
DISPLAY 0.489362 (-3550 4275);
PAINT SKYBLUE (-3550 4275);
FORCEPROP 1 LAST VOLTAGE 16V
J 0
(-3550 4475);
DISPLAY 0.489362 (-3550 4475);
PAINT SKYBLUE (-3550 4475);
FORCEPROP 1 LAST VALUE 0.22UF
J 0
(-3550 4525);
DISPLAY 0.489362 (-3550 4525);
PAINT SKYBLUE (-3550 4525);
FORCEPROP 1 LAST TOLERANCE 10%
J 0
(-3550 4425);
DISPLAY 0.489362 (-3550 4425);
PAINT SKYBLUE (-3550 4425);
FORCEPROP 1 LAST MATERIAL X7R
J 0
(-3550 4375);
DISPLAY 0.489362 (-3550 4375);
PAINT SKYBLUE (-3550 4375);
FORCEPROP 2 LAST CDS_LIB pure_quanta
J 0
(-3600 4450);
DISPLAY INVISIBLE (-3600 4450);
FORCEPROP 1 LAST PATH I30
J 0
(-3550 4600);
DISPLAY 0.978723 (-3550 4600);
PAINT WHITE (-3550 4600);
DISPLAY INVISIBLE (-3550 4600);
FORCEPROP 1 LAST PART_NUMBER CH4223K1B00
J 0
(-3550 4325);
DISPLAY 0.489362 (-3550 4325);
PAINT SKYBLUE (-3550 4325);
DISPLAY INVISIBLE (-3550 4325);
FORCEADD Q_CAP..1
(-3875 5100);
FORCEPROP 1 LAST LOCATION PC611_3
J 0
(-3825 5200);
DISPLAY 0.489362 (-3825 5200);
PAINT SKYBLUE (-3825 5200);
FORCEPROP 0 LAST $SEC 1
J 0
(-3825 5225);
DISPLAY 0.680851 (-3825 5225);
PAINT MONO (-3825 5225);
DISPLAY INVISIBLE (-3825 5225);
FORCEPROP 0 LAST CDS_SEC 1
J 0
(-3825 5225);
DISPLAY 1.021277 (-3825 5225);
DISPLAY INVISIBLE (-3825 5225);
FORCEPROP 1 LASTPIN (-3875 5200) $PN 1
J 0
(-3865 5180);
DISPLAY 0.489362 (-3865 5180);
PAINT MONO (-3865 5180);
FORCEPROP 1 LASTPIN (-3875 5000) $PN 2
J 0
(-3865 4980);
DISPLAY 0.489362 (-3865 4980);
PAINT MONO (-3865 4980);
FORCEPROP 1 LAST MATERIAL X6S
J 0
(-3825 5000);
DISPLAY 0.489362 (-3825 5000);
PAINT SKYBLUE (-3825 5000);
FORCEPROP 1 LAST TOLERANCE 20%
J 0
(-3825 5050);
DISPLAY 0.489362 (-3825 5050);
PAINT SKYBLUE (-3825 5050);
FORCEPROP 1 LAST VOLTAGE 16V
J 0
(-3825 5100);
DISPLAY 0.489362 (-3825 5100);
PAINT SKYBLUE (-3825 5100);
FORCEPROP 1 LAST VALUE 22UF
J 0
(-3825 5150);
DISPLAY 0.489362 (-3825 5150);
PAINT SKYBLUE (-3825 5150);
FORCEPROP 1 LAST PACK_TYPE C0805
J 0
(-3825 4900);
DISPLAY 0.489362 (-3825 4900);
PAINT SKYBLUE (-3825 4900);
FORCEPROP 2 LAST CDS_LIB pure_quanta
J 0
(-3875 5100);
DISPLAY INVISIBLE (-3875 5100);
FORCEPROP 1 LAST PATH I31
J 0
(-3825 5250);
DISPLAY 0.978723 (-3825 5250);
PAINT WHITE (-3825 5250);
DISPLAY INVISIBLE (-3825 5250);
FORCEPROP 1 LAST PART_NUMBER CH6223MEA01
J 0
(-3825 4950);
DISPLAY 0.489362 (-3825 4950);
PAINT SKYBLUE (-3825 4950);
DISPLAY INVISIBLE (-3825 4950);
FORCEADD Q_CAP..1
(-3575 5100);
FORCEPROP 1 LAST LOCATION PC613_3
J 0
(-3525 5200);
DISPLAY 0.489362 (-3525 5200);
PAINT SKYBLUE (-3525 5200);
FORCEPROP 0 LAST $SEC 1
J 0
(-3525 5225);
DISPLAY 0.680851 (-3525 5225);
PAINT MONO (-3525 5225);
DISPLAY INVISIBLE (-3525 5225);
FORCEPROP 0 LAST CDS_SEC 1
J 0
(-3525 5225);
DISPLAY 1.021277 (-3525 5225);
DISPLAY INVISIBLE (-3525 5225);
FORCEPROP 1 LASTPIN (-3575 5200) $PN 1
J 0
(-3565 5180);
DISPLAY 0.489362 (-3565 5180);
PAINT MONO (-3565 5180);
FORCEPROP 1 LASTPIN (-3575 5000) $PN 2
J 0
(-3565 4980);
DISPLAY 0.489362 (-3565 4980);
PAINT MONO (-3565 4980);
FORCEPROP 1 LAST TOLERANCE 20%
J 0
(-3525 5050);
DISPLAY 0.489362 (-3525 5050);
PAINT SKYBLUE (-3525 5050);
FORCEPROP 1 LAST VOLTAGE 16V
J 0
(-3525 5100);
DISPLAY 0.489362 (-3525 5100);
PAINT SKYBLUE (-3525 5100);
FORCEPROP 1 LAST MATERIAL X6S
J 0
(-3525 5000);
DISPLAY 0.489362 (-3525 5000);
PAINT SKYBLUE (-3525 5000);
FORCEPROP 1 LAST PACK_TYPE C0805
J 0
(-3525 4900);
DISPLAY 0.489362 (-3525 4900);
PAINT SKYBLUE (-3525 4900);
FORCEPROP 1 LAST VALUE 22UF
J 0
(-3525 5150);
DISPLAY 0.489362 (-3525 5150);
PAINT SKYBLUE (-3525 5150);
FORCEPROP 2 LAST CDS_LIB pure_quanta
J 0
(-3575 5100);
DISPLAY INVISIBLE (-3575 5100);
FORCEPROP 1 LAST PATH I32
J 0
(-3525 5250);
DISPLAY 0.978723 (-3525 5250);
PAINT WHITE (-3525 5250);
DISPLAY INVISIBLE (-3525 5250);
FORCEPROP 1 LAST PART_NUMBER CH6223MEA01
J 0
(-3525 4950);
DISPLAY 0.489362 (-3525 4950);
PAINT SKYBLUE (-3525 4950);
DISPLAY INVISIBLE (-3525 4950);
FORCEADD UNIVERSAL_GND..1
(-3225 4775);
FORCEPROP 3 LASTPIN (-3225 4825) SIG_NAME GND\g
J 0
(-3215 4835);
DISPLAY 0.659574 (-3215 4835);
PAINT MONO (-3215 4835);
DISPLAY INVISIBLE (-3215 4835);
FORCEPROP 2 LAST CDS_LIB pure_quanta_power
J 0
(-3225 4775);
DISPLAY INVISIBLE (-3225 4775);
FORCEPROP 1 LAST HDL_POWER GND
J 1
(-3200 4700);
DISPLAY 0.872340 (-3200 4700);
PAINT GREEN (-3200 4700);
DISPLAY INVISIBLE (-3200 4700);
FORCEPROP 1 LAST PATH I33
J 0
(-3150 4775);
DISPLAY 0.872340 (-3150 4775);
PAINT AQUA (-3150 4775);
DISPLAY INVISIBLE (-3150 4775);
FORCEADD Q_CAP..1
(-3225 5100);
FORCEPROP 1 LAST LOCATION PC612_3
J 0
(-3175 5200);
DISPLAY 0.489362 (-3175 5200);
PAINT SKYBLUE (-3175 5200);
FORCEPROP 0 LAST $SEC 1
J 0
(-3175 5225);
DISPLAY 0.680851 (-3175 5225);
PAINT MONO (-3175 5225);
DISPLAY INVISIBLE (-3175 5225);
FORCEPROP 0 LAST CDS_SEC 1
J 0
(-3175 5225);
DISPLAY 0.680851 (-3175 5225);
DISPLAY INVISIBLE (-3175 5225);
FORCEPROP 1 LASTPIN (-3225 5200) $PN 1
J 0
(-3215 5180);
DISPLAY 0.787234 (-3215 5180);
PAINT MONO (-3215 5180);
DISPLAY INVISIBLE (-3215 5180);
FORCEPROP 1 LASTPIN (-3225 5000) $PN 2
J 0
(-3215 4980);
DISPLAY 0.787234 (-3215 4980);
PAINT MONO (-3215 4980);
DISPLAY INVISIBLE (-3215 4980);
FORCEPROP 1 LAST TOLERANCE 20%
J 0
(-3175 5050);
DISPLAY 0.489362 (-3175 5050);
PAINT SKYBLUE (-3175 5050);
FORCEPROP 1 LAST VOLTAGE 16V
J 0
(-3175 5100);
DISPLAY 0.489362 (-3175 5100);
PAINT SKYBLUE (-3175 5100);
FORCEPROP 1 LAST VALUE 22UF
J 0
(-3175 5150);
DISPLAY 0.489362 (-3175 5150);
PAINT SKYBLUE (-3175 5150);
FORCEPROP 1 LAST MATERIAL X6S
J 0
(-3175 5000);
DISPLAY 0.489362 (-3175 5000);
PAINT SKYBLUE (-3175 5000);
FORCEPROP 1 LAST PACK_TYPE C0805
J 0
(-3175 4900);
DISPLAY 0.489362 (-3175 4900);
PAINT SKYBLUE (-3175 4900);
FORCEPROP 2 LAST CDS_LIB pure_quanta
J 0
(-3225 5100);
DISPLAY INVISIBLE (-3225 5100);
FORCEPROP 1 LAST PATH I34
J 0
(-3175 5250);
DISPLAY 0.978723 (-3175 5250);
PAINT WHITE (-3175 5250);
DISPLAY INVISIBLE (-3175 5250);
FORCEPROP 1 LAST PART_NUMBER CH6223MEA01
J 0
(-3175 4950);
DISPLAY 0.489362 (-3175 4950);
PAINT SKYBLUE (-3175 4950);
DISPLAY INVISIBLE (-3175 4950);
FORCEADD VCC_CORE..1
(-3225 5400);
FORCEPROP 3 LASTPIN (-3225 5350) SIG_NAME SW_P12V_AUX_PVDDCR_SOC_P0_FLT\g
J 0
(-3215 5360);
DISPLAY 0.659574 (-3215 5360);
PAINT MONO (-3215 5360);
DISPLAY INVISIBLE (-3215 5360);
FORCEPROP 1 LAST HDL_POWER SW_P12V_AUX_PVDDCR_SOC_P0_FLT
J 1
(-3225 5450);
DISPLAY 0.489362 (-3225 5450);
PAINT GREEN (-3225 5450);
FORCEPROP 2 LAST CDS_LIB pure_quanta_power
J 0
(-3225 5400);
DISPLAY INVISIBLE (-3225 5400);
FORCEPROP 1 LAST PATH I35
J 0
(-3175 5425);
DISPLAY 0.872340 (-3175 5425);
PAINT AQUA (-3175 5425);
DISPLAY INVISIBLE (-3175 5425);
FORCEADD VCC_CORE..1
(-1225 4375);
FORCEPROP 3 LASTPIN (-1225 4325) SIG_NAME PVDDCR_SOC_P0\g
J 0
(-1215 4335);
DISPLAY 0.659574 (-1215 4335);
PAINT MONO (-1215 4335);
DISPLAY INVISIBLE (-1215 4335);
FORCEPROP 1 LAST HDL_POWER PVDDCR_SOC_P0
J 1
(-1225 4425);
DISPLAY 0.489362 (-1225 4425);
PAINT GREEN (-1225 4425);
FORCEPROP 2 LAST CDS_LIB pure_quanta_power
J 0
(-1225 4375);
DISPLAY INVISIBLE (-1225 4375);
FORCEPROP 1 LAST PATH I36
J 0
(-1175 4400);
DISPLAY 0.872340 (-1175 4400);
PAINT AQUA (-1175 4400);
DISPLAY INVISIBLE (-1175 4400);
FORCEADD Q_CAP..1
(-4925 5100);
FORCEPROP 1 LAST LOCATION PC609_3
J 0
(-4875 5200);
DISPLAY 0.489362 (-4875 5200);
PAINT SKYBLUE (-4875 5200);
FORCEPROP 0 LAST $SEC 1
J 0
(-4875 5250);
DISPLAY 0.680851 (-4875 5250);
PAINT MONO (-4875 5250);
DISPLAY INVISIBLE (-4875 5250);
FORCEPROP 0 LAST CDS_SEC 1
J 0
(-4875 5250);
DISPLAY 1.021277 (-4875 5250);
DISPLAY INVISIBLE (-4875 5250);
FORCEPROP 1 LASTPIN (-4925 5200) $PN 1
J 0
(-4915 5180);
DISPLAY 0.489362 (-4915 5180);
PAINT MONO (-4915 5180);
FORCEPROP 1 LASTPIN (-4925 5000) $PN 2
J 0
(-4915 4980);
DISPLAY 0.489362 (-4915 4980);
PAINT MONO (-4915 4980);
FORCEPROP 1 LAST VALUE 0.1UF
J 0
(-4875 5150);
DISPLAY 0.489362 (-4875 5150);
PAINT SKYBLUE (-4875 5150);
FORCEPROP 1 LAST VOLTAGE 25V
J 0
(-4875 5100);
DISPLAY 0.489362 (-4875 5100);
PAINT SKYBLUE (-4875 5100);
FORCEPROP 1 LAST TOLERANCE 10%
J 0
(-4875 5050);
DISPLAY 0.489362 (-4875 5050);
PAINT SKYBLUE (-4875 5050);
FORCEPROP 1 LAST PACK_TYPE 0402
J 0
(-4875 4900);
DISPLAY 0.489362 (-4875 4900);
PAINT SKYBLUE (-4875 4900);
FORCEPROP 1 LAST MATERIAL X7R
J 0
(-4875 5000);
DISPLAY 0.489362 (-4875 5000);
PAINT SKYBLUE (-4875 5000);
FORCEPROP 2 LAST CDS_LIB pure_quanta
J 0
(-4925 5100);
DISPLAY INVISIBLE (-4925 5100);
FORCEPROP 1 LAST PATH I37
J 0
(-4875 5250);
DISPLAY 0.978723 (-4875 5250);
PAINT WHITE (-4875 5250);
DISPLAY INVISIBLE (-4875 5250);
FORCEPROP 1 LAST PART_NUMBER CH4104K1B00
J 0
(-4875 4950);
DISPLAY 0.489362 (-4875 4950);
PAINT SKYBLUE (-4875 4950);
DISPLAY INVISIBLE (-4875 4950);
FORCEADD ISL99390FRZTR5935..1
(-5725 4225);
FORCEPROP 1 LAST LOCATION PU51
J 0
(-6025 5100);
DISPLAY 0.489362 (-6025 5100);
PAINT SKYBLUE (-6025 5100);
FORCEPROP 0 LAST $SEC 1
J 0
(-6025 5250);
DISPLAY 0.680851 (-6025 5250);
PAINT MONO (-6025 5250);
DISPLAY INVISIBLE (-6025 5250);
FORCEPROP 0 LAST CDS_SEC 1
J 0
(-6025 5250);
DISPLAY 1.021277 (-6025 5250);
DISPLAY INVISIBLE (-6025 5250);
FORCEPROP 0 LASTPIN (-5325 3775) $PN 2
J 0
(-5315 3785);
DISPLAY 0.489362 (-5315 3785);
PAINT MONO (-5315 3785);
FORCEPROP 0 LASTPIN (-5325 4575) $PN 33
J 0
(-5315 4585);
DISPLAY 0.489362 (-5315 4585);
PAINT MONO (-5315 4585);
FORCEPROP 0 LASTPIN (-6175 3975) $PN 31
J 2
(-6185 3985);
DISPLAY 0.489362 (-6185 3985);
PAINT MONO (-6185 3985);
FORCEPROP 0 LASTPIN (-6175 4375) $PN 35
J 2
(-6185 4385);
DISPLAY 0.489362 (-6185 4385);
PAINT MONO (-6185 4385);
FORCEPROP 0 LASTPIN (-5325 3925) $PN 6
J 0
(-5315 3935);
DISPLAY 0.489362 (-5315 3935);
PAINT MONO (-5315 3935);
FORCEPROP 0 LASTPIN (-5325 3875) $PN 41
J 0
(-5315 3885);
DISPLAY 0.489362 (-5315 3885);
PAINT MONO (-5315 3885);
FORCEPROP 0 LASTPIN (-6175 4225) $PN 38
J 2
(-6185 4235);
DISPLAY 0.489362 (-6185 4235);
PAINT MONO (-6185 4235);
FORCEPROP 0 LASTPIN (-6175 3925) $PN 37
J 2
(-6185 3935);
DISPLAY 0.489362 (-6185 3935);
PAINT MONO (-6185 3935);
FORCEPROP 0 LASTPIN (-5325 3725) $PN 5
J 0
(-5315 3735);
DISPLAY 0.489362 (-5315 3735);
PAINT MONO (-5315 3735);
FORCEPROP 0 LASTPIN (-5325 3675) $PN 7_9-20_24
J 0
(-5315 3685);
DISPLAY 0.489362 (-5315 3685);
PAINT MONO (-5315 3685);
FORCEPROP 0 LASTPIN (-5325 3625) $PN 40
J 0
(-5315 3635);
DISPLAY 0.489362 (-5315 3635);
PAINT MONO (-5315 3635);
FORCEPROP 0 LASTPIN (-5325 4325) $PN 32
J 0
(-5315 4335);
DISPLAY 0.489362 (-5315 4335);
PAINT MONO (-5315 4335);
FORCEPROP 0 LASTPIN (-6175 4875) $PN 4
J 2
(-6185 4885);
DISPLAY 0.489362 (-6185 4885);
PAINT MONO (-6185 4885);
FORCEPROP 0 LASTPIN (-6175 3625) $PN 34
J 2
(-6185 3635);
DISPLAY 0.489362 (-6185 3635);
PAINT MONO (-6185 3635);
FORCEPROP 0 LASTPIN (-6175 4125) $PN 39
J 2
(-6185 4135);
DISPLAY 0.489362 (-6185 4135);
PAINT MONO (-6185 4135);
FORCEPROP 0 LASTPIN (-5325 4225) $PN 10_19
J 0
(-5315 4235);
DISPLAY 0.489362 (-5315 4235);
PAINT MONO (-5315 4235);
FORCEPROP 0 LASTPIN (-6175 3725) $PN 36
J 2
(-6185 3735);
DISPLAY 0.489362 (-6185 3735);
PAINT MONO (-6185 3735);
FORCEPROP 0 LASTPIN (-6175 4575) $PN 3
J 2
(-6185 4585);
DISPLAY 0.489362 (-6185 4585);
PAINT MONO (-6185 4585);
FORCEPROP 0 LASTPIN (-5325 4875) $PN 25_29
J 0
(-5315 4885);
DISPLAY 0.489362 (-5315 4885);
PAINT MONO (-5315 4885);
FORCEPROP 0 LASTPIN (-5325 4825) $PN 30
J 0
(-5315 4835);
DISPLAY 0.489362 (-5315 4835);
PAINT MONO (-5315 4835);
FORCEPROP 0 LASTPIN (-5325 3975) $PN 1
J 0
(-5315 3985);
DISPLAY 0.489362 (-5315 3985);
PAINT MONO (-5315 3985);
FORCEPROP 2 LAST PART_TYPE SMLF
J 0
(-6025 5200);
DISPLAY 1.021277 (-6025 5200);
FORCEPROP 1 LAST MATERIAL IC
J 0
(-6025 4950);
DISPLAY 0.489362 (-6025 4950);
PAINT SKYBLUE (-6025 4950);
FORCEPROP 2 LAST VALUE ISL99390FRZ-TR5935
J 0
(-6025 5150);
DISPLAY 0.489362 (-6025 5150);
PAINT SKYBLUE (-6025 5150);
FORCEPROP 1 LAST CDS_LMAN_SYM_OUTLINE -300,700,250,-650
J 0
(-5725 4225);
DISPLAY 0.468085 (-5725 4225);
PAINT GREEN (-5725 4225);
DISPLAY INVISIBLE (-5725 4225);
FORCEPROP 1 LAST NEEDS_NO_SIZE TRUE
J 0
(-5725 4225);
DISPLAY 0.723404 (-5725 4225);
PAINT GREEN (-5725 4225);
DISPLAY INVISIBLE (-5725 4225);
FORCEPROP 2 LAST CDS_LIB pure_quanta
J 0
(-5725 4225);
DISPLAY INVISIBLE (-5725 4225);
FORCEPROP 1 LAST PATH I38
J 0
(-5725 4225);
DISPLAY 0.723404 (-5725 4225);
PAINT GREEN (-5725 4225);
DISPLAY INVISIBLE (-5725 4225);
FORCEPROP 1 LAST PART_NUMBER AL099390004
J 0
(-6025 5025);
DISPLAY 0.489362 (-6025 5025);
PAINT SKYBLUE (-6025 5025);
DISPLAY INVISIBLE (-6025 5025);
FORCEADD UNIVERSAL_GND..1
(-7225 3750);
FORCEPROP 3 LASTPIN (-7225 3800) SIG_NAME GND\g
J 0
(-7215 3810);
DISPLAY 0.659574 (-7215 3810);
PAINT MONO (-7215 3810);
DISPLAY INVISIBLE (-7215 3810);
FORCEPROP 2 LAST CDS_LIB pure_quanta_power
J 0
(-7225 3750);
DISPLAY INVISIBLE (-7225 3750);
FORCEPROP 1 LAST HDL_POWER GND
J 1
(-7200 3675);
DISPLAY 0.872340 (-7200 3675);
PAINT GREEN (-7200 3675);
DISPLAY INVISIBLE (-7200 3675);
FORCEPROP 1 LAST PATH I4
J 0
(-7150 3750);
DISPLAY 0.872340 (-7150 3750);
PAINT AQUA (-7150 3750);
DISPLAY INVISIBLE (-7150 3750);
FORCEADD OFFPAGE..1
(-6825 3625);
FORCEPROP 2 LAST $XR0 193 
J 0
(-7077 3625);
DISPLAY 0.638298 (-7077 3625);
PAINT MONO (-7077 3625);
FORCEPROP 2 LAST CDS_LIB standard
J 2
(-6825 3625);
DISPLAY INVISIBLE (-6825 3625);
FORCEPROP 1 LAST OFFPAGE TRUE
J 0
(-6500 3500);
DISPLAY 0.872340 (-6500 3500);
PAINT GREEN (-6500 3500);
DISPLAY INVISIBLE (-6500 3500);
FORCEPROP 1 LAST COMMENT_BODY TRUE
J 0
(-6700 3525);
DISPLAY 0.872340 (-6700 3525);
PAINT GREEN (-6700 3525);
DISPLAY INVISIBLE (-6700 3525);
FORCEPROP 2 LAST PATH I5
J 0
(-7100 3675);
DISPLAY 0.680851 (-7100 3675);
DISPLAY INVISIBLE (-7100 3675);
FORCEADD OFFPAGE..2
R 2
(-6850 3725);
FORCEPROP 2 LAST $XR1 193 
J 0
(-7135 3689);
DISPLAY 0.638298 (-7135 3689);
PAINT MONO (-7135 3689);
FORCEPROP 2 LAST $XR0 198 
J 0
(-7135 3725);
DISPLAY 0.638298 (-7135 3725);
PAINT MONO (-7135 3725);
FORCEPROP 2 LAST CDS_LIB standard
J 0
(-6850 3725);
DISPLAY INVISIBLE (-6850 3725);
FORCEPROP 1 LAST OFFPAGE TRUE
J 2
(-7175 3600);
DISPLAY 0.872340 (-7175 3600);
PAINT GREEN (-7175 3600);
DISPLAY INVISIBLE (-7175 3600);
FORCEPROP 1 LAST COMMENT_BODY TRUE
J 2
(-6805 3630);
DISPLAY 0.872340 (-6805 3630);
PAINT GREEN (-6805 3630);
DISPLAY INVISIBLE (-6805 3630);
FORCEPROP 2 LAST PATH I6
J 0
(-7125 3775);
DISPLAY 0.680851 (-7125 3775);
DISPLAY INVISIBLE (-7125 3775);
FORCEADD Q_RES..1
(-6900 3925);
FORCEPROP 1 LAST LOCATION PR365
J 0
(-6950 3975);
DISPLAY 0.489362 (-6950 3975);
PAINT SKYBLUE (-6950 3975);
FORCEPROP 0 LAST $SEC 1
J 0
(-6900 4000);
DISPLAY 0.680851 (-6900 4000);
PAINT MONO (-6900 4000);
DISPLAY INVISIBLE (-6900 4000);
FORCEPROP 0 LAST CDS_SEC 1
J 0
(-6900 4000);
DISPLAY 1.021277 (-6900 4000);
DISPLAY INVISIBLE (-6900 4000);
FORCEPROP 1 LASTPIN (-7000 3925) $PN 1
J 0
(-6988 3937);
DISPLAY 0.489362 (-6988 3937);
PAINT MONO (-6988 3937);
FORCEPROP 1 LASTPIN (-6800 3925) $PN 2
J 0
(-6838 3937);
DISPLAY 0.489362 (-6838 3937);
PAINT MONO (-6838 3937);
FORCEPROP 1 LAST WATTAGE 1/16W
J 0
(-6800 3825);
DISPLAY 0.489362 (-6800 3825);
PAINT SKYBLUE (-6800 3825);
FORCEPROP 1 LAST MATERIAL EMPTY
J 0
(-7200 3825);
DISPLAY 0.489362 (-7200 3825);
PAINT RED (-7200 3825);
FORCEPROP 1 LAST VALUE 8.87K
J 2
(-7025 3950);
DISPLAY 0.489362 (-7025 3950);
PAINT SKYBLUE (-7025 3950);
FORCEPROP 1 LAST PACK_TYPE 0402LF
J 0
(-6800 3875);
DISPLAY 0.489362 (-6800 3875);
PAINT SKYBLUE (-6800 3875);
FORCEPROP 1 LAST TOLERANCE 1%
J 0
(-6775 3950);
DISPLAY 0.489362 (-6775 3950);
PAINT SKYBLUE (-6775 3950);
FORCEPROP 2 LAST CDS_LIB pure_quanta
J 0
(-6900 3925);
DISPLAY INVISIBLE (-6900 3925);
FORCEPROP 1 LAST PATH I7
J 0
(-6950 4075);
DISPLAY 0.978723 (-6950 4075);
PAINT WHITE (-6950 4075);
DISPLAY INVISIBLE (-6950 4075);
FORCEPROP 1 LAST PART_NUMBER CS28872FB01
J 0
(-7200 3875);
DISPLAY 0.489362 (-7200 3875);
PAINT SKYBLUE (-7200 3875);
DISPLAY INVISIBLE (-7200 3875);
FORCEADD UNIVERSAL_GND..1
(-5150 3500);
FORCEPROP 3 LASTPIN (-5150 3550) SIG_NAME GND\g
J 0
(-5140 3560);
DISPLAY 0.659574 (-5140 3560);
PAINT MONO (-5140 3560);
DISPLAY INVISIBLE (-5140 3560);
FORCEPROP 2 LAST CDS_LIB pure_quanta_power
J 0
(-5150 3500);
DISPLAY INVISIBLE (-5150 3500);
FORCEPROP 1 LAST HDL_POWER GND
J 1
(-5125 3425);
DISPLAY 0.872340 (-5125 3425);
PAINT GREEN (-5125 3425);
DISPLAY INVISIBLE (-5125 3425);
FORCEPROP 1 LAST PATH I8
J 0
(-5075 3500);
DISPLAY 0.872340 (-5075 3500);
PAINT AQUA (-5075 3500);
DISPLAY INVISIBLE (-5075 3500);
FORCEADD UNIVERSAL_GND..1
(-4375 3350);
FORCEPROP 3 LASTPIN (-4375 3400) SIG_NAME GND\g
J 0
(-4365 3410);
DISPLAY 0.659574 (-4365 3410);
PAINT MONO (-4365 3410);
DISPLAY INVISIBLE (-4365 3410);
FORCEPROP 2 LAST CDS_LIB pure_quanta_power
J 0
(-4375 3350);
DISPLAY INVISIBLE (-4375 3350);
FORCEPROP 1 LAST HDL_POWER GND
J 1
(-4350 3275);
DISPLAY 0.872340 (-4350 3275);
PAINT GREEN (-4350 3275);
DISPLAY INVISIBLE (-4350 3275);
FORCEPROP 1 LAST PATH I9
J 0
(-4300 3350);
DISPLAY 0.872340 (-4300 3350);
PAINT AQUA (-4300 3350);
DISPLAY INVISIBLE (-4300 3350);
FORCEADD DNS..1
(-4400 4050);
PAINT RED (-4400 4050);
FORCEPROP 2 LAST CDS_LIB mstr_misc
J 0
(-4400 4050);
DISPLAY INVISIBLE (-4400 4050);
FORCEPROP 1 LAST COMMENT_BODY TRUE
R 1
J 0
(-4325 3825);
DISPLAY 0.872340 (-4325 3825);
PAINT GREEN (-4325 3825);
DISPLAY INVISIBLE (-4325 3825);
FORCEADD QUANTA_TITLE_BLOCK_C..1
(0 0);
FORCEPROP 0 LAST CDS_CON_LAST_MODIFIED Thu Sep 14 16:12:18 2023
J 0
(-1885 15);
DISPLAY INVISIBLE (-1885 15);
FORCEPROP 1 LAST CUSTOM_TXT_CDS <CON_LAST_MODIFIED>
J 0
(-1885 15);
DISPLAY 0.978723 (-1885 15);
FORCEPROP 2 LAST CUSTOM_TXT_CDS <XR_PAGE_TITLE>
J 0
(-7890 5250);
DISPLAY 0.638298 (-7890 5250);
PAINT PINK (-7890 5250);
DISPLAY INVISIBLE (-7890 5250);
FORCEPROP 1 LAST CUSTOM_TXT_CDS <NAME_2>
J 0
(-3175 50);
FORCEPROP 1 LAST CUSTOM_TXT_CDS <NAME_1>
J 0
(-3175 175);
FORCEPROP 1 LAST CUSTOM_TXT_CDS <Q_NUMBER>
J 0
(-1403 103);
DISPLAY 1.212766 (-1403 103);
FORCEPROP 1 LAST CUSTOM_TXT_CDS <Q_PROJ>
J 0
(-2382 102);
DISPLAY 1.212766 (-2382 102);
FORCEPROP 1 LAST CUSTOM_TXT_CDS <Q_REV>
J 0
(-184 103);
DISPLAY 1.212766 (-184 103);
FORCEPROP 1 LAST CUSTOM_TXT_CDS <CON_PAGE_NUM> OF <CON_TOTAL_PAGES>
J 0
(-446 18);
DISPLAY 0.978723 (-446 18);
FORCEPROP 1 LAST Q_TITLE PVDDCR_SOC_P0 VR PHASE 3
J 0
(-9325 25);
DISPLAY 2.446809 (-9325 25);
PAINT GREEN (-9325 25);
FORCEPROP 2 LAST PAGE_BORDER TRUE
J 0
(-7890 5250);
DISPLAY 0.638298 (-7890 5250);
PAINT PINK (-7890 5250);
DISPLAY INVISIBLE (-7890 5250);
FORCEPROP 2 LAST CDS_LIB pure_quanta
J 0
(0 0);
DISPLAY INVISIBLE (0 0);
FORCEPROP 1 LAST CDS_LMAN_SYM_OUTLINE -9475,6775,100,-125
J 0
(0 0);
DISPLAY 0.468085 (0 0);
PAINT GREEN (0 0);
DISPLAY INVISIBLE (0 0);
FORCEPROP 2 LAST CDS_XR_PAGE_TITLE CR-199 : @T6G_MB_LIB.T6G(SCH_1):PAGE199
J 0
(-7890 5250);
DISPLAY 0.638298 (-7890 5250);
PAINT PINK (-7890 5250);
DISPLAY INVISIBLE (-7890 5250);
FORCEPROP 1 LAST Q_DEPT BU9
J 1
(-3763 49);
DISPLAY 1.957447 (-3763 49);
PAINT GREEN (-3763 49);
DISPLAY INVISIBLE (-3763 49);
FORCEPROP 1 LAST COMMENT_BODY TRUE
J 0
(12 -13);
DISPLAY 0.978723 (12 -13);
PAINT GREEN (12 -13);
DISPLAY INVISIBLE (12 -13);
FORCEADD DNS..1
(-6900 3900);
PAINT RED (-6900 3900);
FORCEPROP 2 LAST CDS_LIB mstr_misc
J 0
(-6900 3900);
DISPLAY INVISIBLE (-6900 3900);
FORCEPROP 1 LAST COMMENT_BODY TRUE
R 1
J 0
(-6825 3675);
DISPLAY 0.872340 (-6825 3675);
PAINT GREEN (-6825 3675);
DISPLAY INVISIBLE (-6825 3675);
FORCEADD DNS..1
(-4400 3575);
PAINT RED (-4400 3575);
FORCEPROP 2 LAST CDS_LIB mstr_misc
J 0
(-4400 3575);
DISPLAY INVISIBLE (-4400 3575);
FORCEPROP 1 LAST COMMENT_BODY TRUE
R 1
J 0
(-4325 3350);
DISPLAY 0.872340 (-4325 3350);
PAINT GREEN (-4325 3350);
DISPLAY INVISIBLE (-4325 3350);
WIRE 16 -1 (-7225 4475)(-7225 4425);
WIRE 16 -1 (-6875 4950)(-6875 4850);
WIRE 16 -1 (-7550 3850)(-7550 3725);
WIRE 16 -1 (-7000 3925)(-7225 3925);
WIRE 16 -1 (-7225 3925)(-7225 3800);
WIRE 16 -1 (-4375 3475)(-4375 3400);
WIRE 16 -1 (-3225 5275)(-3225 5200);
WIRE 16 -1 (-3225 5350)(-3225 5275);
WIRE 16 -1 (-3225 5275)(-3575 5275);
WIRE 16 -1 (-3575 5275)(-3575 5200);
WIRE 16 -1 (-3875 5275)(-3575 5275);
WIRE 16 -1 (-3875 5275)(-3875 5200);
WIRE 16 -1 (-4200 5275)(-3875 5275);
WIRE 16 -1 (-4200 5200)(-4200 5275);
WIRE 16 -1 (-4525 5275)(-4200 5275);
WIRE 16 -1 (-4525 5200)(-4525 5275);
WIRE 16 -1 (-4925 5275)(-4525 5275);
WIRE 16 -1 (-4925 5200)(-4925 5275);
WIRE 16 -1 (-5225 5275)(-4925 5275);
WIRE 16 -1 (-5225 5275)(-5225 4875);
WIRE 16 -1 (-5325 4875)(-5225 4875);
WIRE 16 -1 (-5225 4875)(-5225 4825);
WIRE 16 -1 (-5225 4825)(-5325 4825);
WIRE 16 -1 (-3575 5000)(-3575 4875);
WIRE 16 -1 (-3225 4875)(-3575 4875);
WIRE 16 -1 (-3575 4875)(-3875 4875);
WIRE 16 -1 (-3875 5000)(-3875 4875);
WIRE 16 -1 (-4200 4875)(-3875 4875);
WIRE 16 -1 (-3225 5000)(-3225 4875);
WIRE 16 -1 (-3225 4875)(-3225 4825);
WIRE 16 -1 (-4200 5000)(-4200 4875);
WIRE 16 -1 (-4525 4875)(-4200 4875);
WIRE 16 -1 (-4525 5000)(-4525 4875);
WIRE 16 -1 (-4925 4875)(-4525 4875);
WIRE 16 -1 (-4925 5000)(-4925 4875);
WIRE 16 -1 (-5325 4575)(-4525 4575);
FORCEPROP 2 LAST SIG_NAME SW_PVDDCR_SOC_P0_BOOT3
J 0
(-5210 4585);
DISPLAY 0.489362 (-5210 4585);
FORCEPROP 2 LASTPROP $XRERR UNIQUE?
J 0
(-5450 4585);
DISPLAY 0.638298 (-5450 4585);
PAINT MONO (-5450 4585);
DISPLAY INVISIBLE (-5450 4585);
WIRE 16 -1 (-3600 4575)(-3600 4550);
WIRE 16 -1 (-4325 4575)(-3600 4575);
FORCEPROP 2 LAST SIG_NAME SW_PVDDCR_SOC_P0_BOOT3_RC
J 2
(-3635 4585);
DISPLAY 0.489362 (-3635 4585);
FORCEPROP 2 LASTPROP $XRERR UNIQUE?
J 0
(-3875 4585);
DISPLAY 0.638298 (-3875 4585);
PAINT MONO (-3875 4585);
DISPLAY INVISIBLE (-3875 4585);
WIRE 16 -1 (-3600 4350)(-3600 4325);
WIRE 16 -1 (-3600 4325)(-5325 4325);
FORCEPROP 2 LAST SIG_NAME SW_PVDDCR_SOC_P0_PH3
J 0
(-5210 4335);
DISPLAY 0.489362 (-5210 4335);
FORCEPROP 2 LASTPROP $XRERR UNIQUE?
J 0
(-5450 4335);
DISPLAY 0.638298 (-5450 4335);
PAINT MONO (-5450 4335);
DISPLAY INVISIBLE (-5450 4335);
WIRE 16 -1 (-4050 3275)(-4600 3275);
FORCEPROP 2 LAST SIG_NAME PVDDCR_SOC_P0_VOS3
J 0
(-5210 4000);
DISPLAY 0.489362 (-5210 4000);
FORCEPROP 2 LASTPROP $XRERR UNIQUE?
J 0
(-5450 4000);
DISPLAY 0.638298 (-5450 4000);
PAINT MONO (-5450 4000);
DISPLAY INVISIBLE (-5450 4000);
WIRE 16 -1 (-4600 3275)(-4600 3975);
WIRE 16 -1 (-5325 3975)(-4600 3975);
WIRE 16 -1 (-5325 4225)(-4375 4225);
FORCEPROP 2 LAST SIG_NAME SW_PVDDCR_SOC_P0_SW3
J 0
(-5210 4250);
DISPLAY 0.489362 (-5210 4250);
FORCEPROP 2 LASTPROP $XRERR UNIQUE?
J 0
(-5450 4250);
DISPLAY 0.638298 (-5450 4250);
PAINT MONO (-5450 4250);
DISPLAY INVISIBLE (-5450 4250);
WIRE 16 -1 (-4375 4225)(-3225 4225);
WIRE 16 -1 (-4375 4225)(-4375 4150);
WIRE 16 -1 (-2425 3975)(-2000 3975);
FORCEPROP 2 LAST SIG_NAME IND_SOC_P0_CPL3
J 0
(-2335 3985);
DISPLAY 0.489362 (-2335 3985);
WIRE 16 -1 (-3675 3975)(-3225 3975);
FORCEPROP 2 LAST SIG_NAME IND_SOC_P0_CPL0
J 0
(-3685 3985);
DISPLAY 0.489362 (-3685 3985);
FORCEPROP 2 LASTPROP $XRERR UNIQUE?
J 0
(-3925 3985);
DISPLAY 0.638298 (-3925 3985);
PAINT MONO (-3925 3985);
DISPLAY INVISIBLE (-3925 3985);
WIRE 16 -1 (-6175 4225)(-6825 4225);
FORCEPROP 2 LAST SIG_NAME PVDDCR_SOC_P0_IMON3
J 2
(-6235 4235);
DISPLAY 0.489362 (-6235 4235);
WIRE 16 -1 (-4375 3950)(-4375 3675);
FORCEPROP 2 LAST SIG_NAME SW_PVDDCR_SOC_P0_SW3_RC
J 0
(-4335 3785);
DISPLAY 0.489362 (-4335 3785);
FORCEPROP 2 LASTPROP $XRERR UNIQUE?
J 0
(-4575 3785);
DISPLAY 0.638298 (-4575 3785);
PAINT MONO (-4575 3785);
DISPLAY INVISIBLE (-4575 3785);
WIRE 16 -1 (-5325 3875)(-4800 3875);
FORCEPROP 2 LAST SIG_NAME NC_PVDDCR_SOC_P0_GL2_3
J 0
(-5210 3885);
DISPLAY 0.489362 (-5210 3885);
FORCEPROP 2 LASTPROP $XRERR UNIQUE?
J 0
(-4770 3875);
DISPLAY 0.638298 (-4770 3875);
PAINT MONO (-4770 3875);
DISPLAY INVISIBLE (-4770 3875);
WIRE 16 -1 (-5325 3925)(-4800 3925);
FORCEPROP 2 LAST SIG_NAME NC_PVDDCR_SOC_P0_GL1_3
J 0
(-5210 3935);
DISPLAY 0.489362 (-5210 3935);
FORCEPROP 2 LASTPROP $XRERR UNIQUE?
J 0
(-4770 3925);
DISPLAY 0.638298 (-4770 3925);
PAINT MONO (-4770 3925);
DISPLAY INVISIBLE (-4770 3925);
WIRE 16 -1 (-6800 3925)(-6175 3925);
FORCEPROP 2 LAST SIG_NAME PVDDCR_SOC_P0_LSET3
J 2
(-6235 3935);
DISPLAY 0.489362 (-6235 3935);
FORCEPROP 2 LASTPROP $XRERR UNIQUE?
J 0
(-6475 3935);
DISPLAY 0.638298 (-6475 3935);
PAINT MONO (-6475 3935);
DISPLAY INVISIBLE (-6475 3935);
WIRE 16 -1 (-6175 3975)(-6625 3975);
FORCEPROP 2 LAST SIG_NAME NC_PVDDCR_SOC_P0_DNC3
J 2
(-6235 3985);
DISPLAY 0.489362 (-6235 3985);
FORCEPROP 2 LASTPROP $XRERR UNIQUE?
J 0
(-6865 3975);
DISPLAY 0.638298 (-6865 3975);
PAINT MONO (-6865 3975);
DISPLAY INVISIBLE (-6865 3975);
WIRE 16 -1 (-6175 3725)(-6800 3725);
FORCEPROP 2 LAST SIG_NAME PVDDCR_SOC_P0_TEMP1
J 2
(-6235 3735);
DISPLAY 0.489362 (-6235 3735);
WIRE 16 -1 (-6175 3625)(-6775 3625);
FORCEPROP 2 LAST SIG_NAME PVDDCR_SOC_P0_PWM3
J 2
(-6235 3635);
DISPLAY 0.489362 (-6235 3635);
WIRE 16 -1 (-7725 4125)(-7550 4125);
WIRE 16 -1 (-6175 4125)(-7550 4125);
FORCEPROP 2 LAST SIG_NAME PVDDCR_CPU0_P0_VCCS
J 2
(-6235 4135);
DISPLAY 0.489362 (-6235 4135);
WIRE 16 -1 (-7550 4050)(-7550 4125);
WIRE 16 -1 (-7225 4750)(-6750 4750);
WIRE 16 -1 (-7225 4950)(-7225 4750);
WIRE 16 -1 (-7225 4750)(-7225 4675);
WIRE 16 -1 (-6750 4750)(-6750 4575);
FORCEPROP 2 LAST SIG_NAME PVDDCR_SOC_P0_VCC3
J 2
(-6260 4585);
DISPLAY 0.489362 (-6260 4585);
FORCEPROP 2 LASTPROP $XRERR UNIQUE?
J 0
(-6500 4585);
DISPLAY 0.638298 (-6500 4585);
PAINT MONO (-6500 4585);
DISPLAY INVISIBLE (-6500 4585);
WIRE 16 -1 (-6750 4575)(-6175 4575);
WIRE 16 -1 (-6750 4575)(-6750 4375);
WIRE 16 -1 (-6750 4375)(-6175 4375);
WIRE 16 -1 (-5150 3625)(-5150 3675);
WIRE 16 -1 (-5325 3625)(-5150 3625);
WIRE 16 -1 (-5150 3550)(-5150 3625);
WIRE 16 -1 (-5150 3675)(-5150 3725);
WIRE 16 -1 (-5325 3675)(-5150 3675);
WIRE 16 -1 (-5150 3775)(-5150 3725);
WIRE 16 -1 (-5325 3725)(-5150 3725);
WIRE 16 -1 (-5150 3775)(-5325 3775);
WIRE 16 -1 (-1725 4225)(-1650 4225);
WIRE 16 -1 (-2425 4225)(-1725 4225);
WIRE 16 -1 (-1725 4225)(-1725 3275);
WIRE 16 -1 (-1650 4225)(-1225 4225);
WIRE 16 -1 (-1650 4225)(-1650 4150);
WIRE 16 -1 (-1225 4325)(-1225 4225);
WIRE 16 -1 (-1225 4225)(-1225 4150);
WIRE 16 -1 (-1725 3275)(-3850 3275);
WIRE 16 -1 (-1225 3950)(-1225 3825);
WIRE 16 -1 (-1225 3750)(-1225 3825);
WIRE 16 -1 (-1225 3825)(-1650 3825);
WIRE 16 -1 (-1650 3950)(-1650 3825);
WIRE 16 -1 (-3975 3975)(-3875 3975);
WIRE 16 -1 (-3975 3925)(-3975 3975);
WIRE 16 -1 (-7225 5150)(-7225 5275);
WIRE 16 -1 (-6875 5275)(-7225 5275);
WIRE 16 -1 (-7225 5400)(-7225 5275);
WIRE 16 -1 (-6875 5150)(-6875 5275);
WIRE 16 -1 (-6525 5275)(-6875 5275);
WIRE 16 -1 (-6525 4875)(-6525 5275);
WIRE 16 -1 (-6525 4875)(-6175 4875);
DOT 1 (-7550 4125);
DOT 1 (-5150 3625);
DOT 1 (-5150 3675);
DOT 1 (-5150 3725);
DOT 1 (-7225 4750);
DOT 1 (-7225 5275);
DOT 1 (-6750 4575);
DOT 1 (-6875 5275);
DOT 1 (-5225 4875);
DOT 1 (-4525 4875);
DOT 1 (-4375 4225);
DOT 1 (-4200 4875);
DOT 1 (-4525 5275);
DOT 1 (-4200 5275);
DOT 1 (-1225 3825);
DOT 1 (-3875 4875);
DOT 1 (-3575 4875);
DOT 1 (-3225 4875);
DOT 1 (-3875 5275);
DOT 1 (-3575 5275);
DOT 1 (-3225 5275);
DOT 1 (-1725 4225);
DOT 1 (-1650 4225);
DOT 1 (-1225 4225);
DOT 1 (-4925 5275);
FORCENOTE
ISAT:30A@100C
(-3775 3875) 0;
DISPLAY LEFT (-3775 3875);
DISPLAY 0.638298 (-3775 3875);
PAINT WHITE (-3775 3875);
FORCENOTE
6.5*6.5*10.0
(-3775 3825) 0;
DISPLAY LEFT (-3775 3825);
DISPLAY 0.638298 (-3775 3825);
PAINT WHITE (-3775 3825);
FORCENOTE
DCR=0.17M OHM
(-3775 3775) 0;
DISPLAY LEFT (-3775 3775);
DISPLAY 0.638298 (-3775 3775);
PAINT WHITE (-3775 3775);
FORCENOTE
HCME656510Q-221QL
(-3775 3925) 0;
DISPLAY LEFT (-3775 3925);
DISPLAY 0.638298 (-3775 3925);
PAINT WHITE (-3775 3925);
FORCENOTE
2ND=CV+22Y0EZ01
(-3775 3725) 0;
DISPLAY LEFT (-3775 3725);
DISPLAY 0.638298 (-3775 3725);
PAINT WHITE (-3775 3725);
FORCENOTE
PGL6303.151HLT
(-2400 4550) 0;
DISPLAY LEFT (-2400 4550);
DISPLAY 0.638298 (-2400 4550);
PAINT WHITE (-2400 4550);
FORCENOTE
ISAT:70A@100C
(-2400 4500) 0;
DISPLAY LEFT (-2400 4500);
DISPLAY 0.638298 (-2400 4500);
PAINT WHITE (-2400 4500);
FORCENOTE
11.0*7.5*12.5
(-2400 4450) 0;
DISPLAY LEFT (-2400 4450);
DISPLAY 0.638298 (-2400 4450);
PAINT WHITE (-2400 4450);
FORCENOTE
2ND=CV+15^0TZ01
(-2400 4300) 0;
DISPLAY LEFT (-2400 4300);
DISPLAY 0.638298 (-2400 4300);
PAINT WHITE (-2400 4300);
FORCENOTE
DCR=2-3,0.27M OHM
(-2400 4350) 0;
DISPLAY LEFT (-2400 4350);
DISPLAY 0.638298 (-2400 4350);
PAINT WHITE (-2400 4350);
FORCENOTE
DCR=1-4,0.105M OHM
(-2400 4400) 0;
DISPLAY LEFT (-2400 4400);
DISPLAY 0.638298 (-2400 4400);
PAINT WHITE (-2400 4400);
FORCENOTE
PVDDCR_SOC_P0_PHASE3
(-6300 5625) 0;
DISPLAY LEFT (-6300 5625);
DISPLAY 1.595745 (-6300 5625);
PAINT WHITE (-6300 5625);
QUIT
